(kicad_pcb
	(version 20260206)
	(generator "pcbnew")
	(generator_version "10.0")
	(general
		(thickness 1.6)
		(legacy_teardrops no)
	)
	(paper "A4")
	(title_block
		(title "Bryce Canyon_F.DPB_16315-1-OCP.brd")
		(comment 1 "Bryce Canyon / footprints 1169-1175 of 2223")
	)
	(layers
		(0 "F.Cu" signal "TOP")
		(4 "In1.Cu" signal "L2GND")
		(6 "In2.Cu" signal "L3")
		(8 "In3.Cu" signal "L4GND")
		(10 "In4.Cu" signal "L5")
		(12 "In5.Cu" signal "L6VCC")
		(14 "In6.Cu" signal "L7VCC")
		(16 "In7.Cu" signal "L8")
		(18 "In8.Cu" signal "L9GND")
		(20 "In9.Cu" signal "L10")
		(22 "In10.Cu" signal "L11GND")
		(2 "B.Cu" signal "BOTTOM")
		(9 "F.Adhes" user "F.Adhesive")
		(11 "B.Adhes" user "B.Adhesive")
		(13 "F.Paste" user "Package Geometry/Pastemask Top")
		(15 "B.Paste" user "Package Geometry/Pastemask Bottom")
		(5 "F.SilkS" user "Ref Des/Silkscreen Top")
		(7 "B.SilkS" user "Ref Des/Silkscreen Bottom")
		(1 "F.Mask" user "Board Geometry/Soldermask Top")
		(3 "B.Mask" user "Board Geometry/Soldermask Bottom")
		(17 "Dwgs.User" user "User.Drawings")
		(19 "Cmts.User" user "User.Comments")
		(21 "Eco1.User" user "User.Eco1")
		(23 "Eco2.User" user "User.Eco2")
		(25 "Edge.Cuts" user "Board Geometry/Outline")
		(27 "Margin" user)
		(31 "F.CrtYd" user "Package Geometry/Place Bound Top")
		(29 "B.CrtYd" user "Package Geometry/Place Bound Bottom")
		(35 "F.Fab" user "Ref Des/Assembly Top")
		(33 "B.Fab" user "Ref Des/Assembly Bottom")
	)
	(footprint ""
		(layer "F.Cu")
		(at 225.451162 -217.608658 -90)
		(property "Reference" "R411"
			(at 0 0 270)
			(layer "F.SilkS")
			(hide yes)
			(effects
				(font
					(size 1.27 1.27)
				)
			)
		)
		(property "Value" "10KR2F-2-GP"
			(at 0.064008 -3.993896 270)
			(unlocked yes)
			(layer "F.Fab")
			(hide yes)
			(effects
				(font
					(size 1.016 1.016)
					(thickness 0.1524)
				)
			)
		)
		(property "Device Type" "R402H16"
			(at 0.064008 -5.517896 270)
			(unlocked yes)
			(layer "F.Fab")
			(hide yes)
			(effects
				(font
					(size 1.016 1.016)
					(thickness 0.1524)
				)
			)
		)
		(duplicate_pad_numbers_are_jumpers no)
		(fp_line
			(start -0.508 -0.9398)
			(end -0.508 0.9398)
			(stroke
				(width 0.1524)
				(type default)
			)
			(layer "F.SilkS")
		)
		(fp_line
			(start 0.508 -0.9398)
			(end -0.508 -0.9398)
			(stroke
				(width 0.1524)
				(type default)
			)
			(layer "F.SilkS")
		)
		(fp_rect
			(start -0.508 0.9398)
			(end 0.508 -0.9398)
			(stroke
				(width 0)
				(type default)
			)
			(fill no)
			(layer "F.CrtYd")
		)
		(fp_rect
			(start -0.508 0.9398)
			(end 0.508 -0.9398)
			(stroke
				(width 0)
				(type default)
			)
			(fill no)
			(layer "F.Fab")
		)
		(pad "1" smd custom
			(at 0 -0.4445 270)
			(size 0.1397 0.1397)
			(layers "F.Cu" "F.Mask" "F.Paste")
			(net "P3V3_STBY_A")
			(options
				(clearance outline)
				(anchor circle)
			)
			(primitives
				(gr_poly
					(pts
						(arc
							(start -0.1778 -0.2794)
							(mid -0.249642 -0.249642)
							(end -0.2794 -0.1778)
						)
						(arc
							(start -0.2794 0.1778)
							(mid -0.249642 0.249642)
							(end -0.1778 0.2794)
						)
						(arc
							(start 0.1778 0.2794)
							(mid 0.249642 0.249642)
							(end 0.2794 0.1778)
						)
						(arc
							(start 0.2794 -0.1778)
							(mid 0.249642 -0.249642)
							(end 0.1778 -0.2794)
						)
					)
					(width 0)
					(fill yes)
				)
			)
		)
		(pad "2" smd custom
			(at 0 0.4445 270)
			(size 0.1397 0.1397)
			(layers "F.Cu" "F.Mask" "F.Paste")
			(net "I2C_SCC_BUFF_READY")
			(options
				(clearance outline)
				(anchor circle)
			)
			(primitives
				(gr_poly
					(pts
						(arc
							(start -0.1778 -0.2794)
							(mid -0.249642 -0.249642)
							(end -0.2794 -0.1778)
						)
						(arc
							(start -0.2794 0.1778)
							(mid -0.249642 0.249642)
							(end -0.1778 0.2794)
						)
						(arc
							(start 0.1778 0.2794)
							(mid 0.249642 0.249642)
							(end 0.2794 0.1778)
						)
						(arc
							(start 0.2794 -0.1778)
							(mid 0.249642 -0.249642)
							(end 0.1778 -0.2794)
						)
					)
					(width 0)
					(fill yes)
				)
			)
		)
	)
	(footprint ""
		(layer "F.Cu")
		(at 83.255866 -17.35963 90)
		(property "Reference" "R51"
			(at 0 0 90)
			(layer "F.SilkS")
			(hide yes)
			(effects
				(font
					(size 1.27 1.27)
				)
			)
		)
		(property "Value" "4K7R2F-GP"
			(at 0.064008 -3.993896 90)
			(unlocked yes)
			(layer "F.Fab")
			(hide yes)
			(effects
				(font
					(size 1.016 1.016)
					(thickness 0.1524)
				)
			)
		)
		(property "Device Type" "R402H16"
			(at 0.064008 -5.517896 90)
			(unlocked yes)
			(layer "F.Fab")
			(hide yes)
			(effects
				(font
					(size 1.016 1.016)
					(thickness 0.1524)
				)
			)
		)
		(duplicate_pad_numbers_are_jumpers no)
		(fp_line
			(start 0.508 -0.9398)
			(end -0.508 -0.9398)
			(stroke
				(width 0.1524)
				(type default)
			)
			(layer "F.SilkS")
		)
		(fp_line
			(start -0.508 -0.9398)
			(end -0.508 0.9398)
			(stroke
				(width 0.1524)
				(type default)
			)
			(layer "F.SilkS")
		)
		(fp_rect
			(start -0.508 0.9398)
			(end 0.508 -0.9398)
			(stroke
				(width 0)
				(type default)
			)
			(fill no)
			(layer "F.CrtYd")
		)
		(fp_rect
			(start -0.508 0.9398)
			(end 0.508 -0.9398)
			(stroke
				(width 0)
				(type default)
			)
			(fill no)
			(layer "F.Fab")
		)
		(pad "1" smd custom
			(at 0 -0.4445 90)
			(size 0.1397 0.1397)
			(layers "F.Cu" "F.Mask" "F.Paste")
			(net "P3V3_STBY_A")
			(options
				(clearance outline)
				(anchor circle)
			)
			(primitives
				(gr_poly
					(pts
						(arc
							(start -0.1778 -0.2794)
							(mid -0.249642 -0.249642)
							(end -0.2794 -0.1778)
						)
						(arc
							(start -0.2794 0.1778)
							(mid -0.249642 0.249642)
							(end -0.1778 0.2794)
						)
						(arc
							(start 0.1778 0.2794)
							(mid 0.249642 0.249642)
							(end 0.2794 0.1778)
						)
						(arc
							(start 0.2794 -0.1778)
							(mid 0.249642 -0.249642)
							(end 0.1778 -0.2794)
						)
					)
					(width 0)
					(fill yes)
				)
			)
		)
		(pad "2" smd custom
			(at 0 0.4445 90)
			(size 0.1397 0.1397)
			(layers "F.Cu" "F.Mask" "F.Paste")
			(net "IO_EXP10_A2")
			(options
				(clearance outline)
				(anchor circle)
			)
			(primitives
				(gr_poly
					(pts
						(arc
							(start -0.1778 -0.2794)
							(mid -0.249642 -0.249642)
							(end -0.2794 -0.1778)
						)
						(arc
							(start -0.2794 0.1778)
							(mid -0.249642 0.249642)
							(end -0.1778 0.2794)
						)
						(arc
							(start 0.1778 0.2794)
							(mid 0.249642 0.249642)
							(end 0.2794 0.1778)
						)
						(arc
							(start 0.2794 -0.1778)
							(mid 0.249642 -0.249642)
							(end 0.1778 -0.2794)
						)
					)
					(width 0)
					(fill yes)
				)
			)
		)
	)
	(footprint ""
		(layer "F.Cu")
		(at 338.709 -57.851294 90)
		(property "Reference" "C439"
			(at 0 0 90)
			(layer "F.SilkS")
			(hide yes)
			(effects
				(font
					(size 1.27 1.27)
				)
			)
		)
		(property "Value" "SCD033U25V2KX-GP"
			(at 1.1811 -2.7051 90)
			(unlocked yes)
			(layer "F.Fab")
			(hide yes)
			(effects
				(font
					(size 1.016 1.016)
					(thickness 0.1524)
				)
			)
		)
		(property "Device Type" "C402H22"
			(at 1.1811 -4.2291 90)
			(unlocked yes)
			(layer "F.Fab")
			(hide yes)
			(effects
				(font
					(size 1.016 1.016)
					(thickness 0.1524)
				)
			)
		)
		(duplicate_pad_numbers_are_jumpers no)
		(fp_rect
			(start -0.4318 0.9525)
			(end 0.4318 -0.9525)
			(stroke
				(width 0)
				(type default)
			)
			(fill no)
			(layer "F.CrtYd")
		)
		(fp_rect
			(start -0.4318 0.9525)
			(end 0.4318 -0.9525)
			(stroke
				(width 0)
				(type default)
			)
			(fill no)
			(layer "F.Fab")
		)
		(pad "1" smd custom
			(at 0 -0.4445 90)
			(size 0.1524 0.1524)
			(layers "F.Cu" "F.Mask" "F.Paste")
			(net "P12V_A")
			(options
				(clearance outline)
				(anchor circle)
			)
			(primitives
				(gr_poly
					(pts
						(arc
							(start 0.3048 -0.2032)
							(mid 0.275042 -0.275042)
							(end 0.2032 -0.3048)
						)
						(arc
							(start -0.2032 -0.3048)
							(mid -0.275042 -0.275042)
							(end -0.3048 -0.2032)
						)
						(arc
							(start -0.3048 0.2032)
							(mid -0.275042 0.275042)
							(end -0.2032 0.3048)
						)
						(arc
							(start 0.2032 0.3048)
							(mid 0.275042 0.275042)
							(end 0.3048 0.2032)
						)
					)
					(width 0)
					(fill yes)
				)
			)
		)
		(pad "2" smd custom
			(at 0 0.4445 90)
			(size 0.1524 0.1524)
			(layers "F.Cu" "F.Mask" "F.Paste")
			(net "SW_HDD_N30")
			(options
				(clearance outline)
				(anchor circle)
			)
			(primitives
				(gr_poly
					(pts
						(arc
							(start 0.3048 -0.2032)
							(mid 0.275042 -0.275042)
							(end 0.2032 -0.3048)
						)
						(arc
							(start -0.2032 -0.3048)
							(mid -0.275042 -0.275042)
							(end -0.3048 -0.2032)
						)
						(arc
							(start -0.3048 0.2032)
							(mid -0.275042 0.275042)
							(end -0.2032 0.3048)
						)
						(arc
							(start 0.2032 0.3048)
							(mid 0.275042 0.275042)
							(end 0.3048 0.2032)
						)
					)
					(width 0)
					(fill yes)
				)
			)
		)
	)
	(footprint ""
		(layer "F.Cu")
		(at 143.049498 -53.126894 -90)
		(property "Reference" "C412"
			(at 0 0 270)
			(layer "F.SilkS")
			(hide yes)
			(effects
				(font
					(size 1.27 1.27)
				)
			)
		)
		(property "Value" "SCD033U25V2KX-GP"
			(at 1.1811 -2.7051 270)
			(unlocked yes)
			(layer "F.Fab")
			(hide yes)
			(effects
				(font
					(size 1.016 1.016)
					(thickness 0.1524)
				)
			)
		)
		(property "Device Type" "C402H22"
			(at 1.1811 -4.2291 270)
			(unlocked yes)
			(layer "F.Fab")
			(hide yes)
			(effects
				(font
					(size 1.016 1.016)
					(thickness 0.1524)
				)
			)
		)
		(duplicate_pad_numbers_are_jumpers no)
		(fp_rect
			(start -0.4318 0.9525)
			(end 0.4318 -0.9525)
			(stroke
				(width 0)
				(type default)
			)
			(fill no)
			(layer "F.CrtYd")
		)
		(fp_rect
			(start -0.4318 0.9525)
			(end 0.4318 -0.9525)
			(stroke
				(width 0)
				(type default)
			)
			(fill no)
			(layer "F.Fab")
		)
		(pad "1" smd custom
			(at 0 -0.4445 270)
			(size 0.1524 0.1524)
			(layers "F.Cu" "F.Mask" "F.Paste")
			(net "SW_HDD_P28")
			(options
				(clearance outline)
				(anchor circle)
			)
			(primitives
				(gr_poly
					(pts
						(arc
							(start 0.3048 -0.2032)
							(mid 0.275042 -0.275042)
							(end 0.2032 -0.3048)
						)
						(arc
							(start -0.2032 -0.3048)
							(mid -0.275042 -0.275042)
							(end -0.3048 -0.2032)
						)
						(arc
							(start -0.3048 0.2032)
							(mid -0.275042 0.275042)
							(end -0.2032 0.3048)
						)
						(arc
							(start 0.2032 0.3048)
							(mid 0.275042 0.275042)
							(end 0.3048 0.2032)
						)
					)
					(width 0)
					(fill yes)
				)
			)
		)
		(pad "2" smd custom
			(at 0 0.4445 270)
			(size 0.1524 0.1524)
			(layers "F.Cu" "F.Mask" "F.Paste")
			(net "GND")
			(options
				(clearance outline)
				(anchor circle)
			)
			(primitives
				(gr_poly
					(pts
						(arc
							(start 0.3048 -0.2032)
							(mid 0.275042 -0.275042)
							(end 0.2032 -0.3048)
						)
						(arc
							(start -0.2032 -0.3048)
							(mid -0.275042 -0.275042)
							(end -0.3048 -0.2032)
						)
						(arc
							(start -0.3048 0.2032)
							(mid -0.275042 0.275042)
							(end -0.2032 0.3048)
						)
						(arc
							(start 0.2032 0.3048)
							(mid 0.275042 0.275042)
							(end 0.3048 0.2032)
						)
					)
					(width 0)
					(fill yes)
				)
			)
		)
	)
	(footprint ""
		(layer "F.Cu")
		(at 377.835414 -136.489948)
		(property "Reference" "C24"
			(at 0 0 0)
			(layer "F.SilkS")
			(hide yes)
			(effects
				(font
					(size 1.27 1.27)
				)
			)
		)
		(property "Value" "SCD1U16V2KX-3GP"
			(at 1.1811 -2.7051 0)
			(unlocked yes)
			(layer "F.Fab")
			(hide yes)
			(effects
				(font
					(size 1.016 1.016)
					(thickness 0.1524)
				)
			)
		)
		(property "Device Type" "C402H22"
			(at 1.1811 -4.2291 0)
			(unlocked yes)
			(layer "F.Fab")
			(hide yes)
			(effects
				(font
					(size 1.016 1.016)
					(thickness 0.1524)
				)
			)
		)
		(duplicate_pad_numbers_are_jumpers no)
		(fp_rect
			(start -0.4318 0.9525)
			(end 0.4318 -0.9525)
			(stroke
				(width 0)
				(type default)
			)
			(fill no)
			(layer "F.CrtYd")
		)
		(fp_rect
			(start -0.4318 0.9525)
			(end 0.4318 -0.9525)
			(stroke
				(width 0)
				(type default)
			)
			(fill no)
			(layer "F.Fab")
		)
		(pad "1" smd custom
			(at 0 -0.4445)
			(size 0.1524 0.1524)
			(layers "F.Cu" "F.Mask" "F.Paste")
			(net "P3V3_B_BIAS")
			(options
				(clearance outline)
				(anchor circle)
			)
			(primitives
				(gr_poly
					(pts
						(arc
							(start 0.3048 -0.2032)
							(mid 0.275042 -0.275042)
							(end 0.2032 -0.3048)
						)
						(arc
							(start -0.2032 -0.3048)
							(mid -0.275042 -0.275042)
							(end -0.3048 -0.2032)
						)
						(arc
							(start -0.3048 0.2032)
							(mid -0.275042 0.275042)
							(end -0.2032 0.3048)
						)
						(arc
							(start 0.2032 0.3048)
							(mid 0.275042 0.275042)
							(end 0.3048 0.2032)
						)
					)
					(width 0)
					(fill yes)
				)
			)
		)
		(pad "2" smd custom
			(at 0 0.4445)
			(size 0.1524 0.1524)
			(layers "F.Cu" "F.Mask" "F.Paste")
			(net "GND")
			(options
				(clearance outline)
				(anchor circle)
			)
			(primitives
				(gr_poly
					(pts
						(arc
							(start 0.3048 -0.2032)
							(mid 0.275042 -0.275042)
							(end 0.2032 -0.3048)
						)
						(arc
							(start -0.2032 -0.3048)
							(mid -0.275042 -0.275042)
							(end -0.3048 -0.2032)
						)
						(arc
							(start -0.3048 0.2032)
							(mid -0.275042 0.275042)
							(end -0.2032 0.3048)
						)
						(arc
							(start 0.2032 0.3048)
							(mid 0.275042 0.275042)
							(end 0.3048 0.2032)
						)
					)
					(width 0)
					(fill yes)
				)
			)
		)
	)
	(footprint ""
		(layer "F.Cu")
		(at 82.248502 -31.399988 180)
		(property "Reference" "R1298"
			(at 0 0 180)
			(layer "F.SilkS")
			(hide yes)
			(effects
				(font
					(size 1.27 1.27)
				)
			)
		)
		(property "Value" "2K2R2F-GP"
			(at 0.064008 -3.993896 180)
			(unlocked yes)
			(layer "F.Fab")
			(hide yes)
			(effects
				(font
					(size 1.016 1.016)
					(thickness 0.1524)
				)
			)
		)
		(property "Device Type" "R402H16"
			(at 0.064008 -5.517896 180)
			(unlocked yes)
			(layer "F.Fab")
			(hide yes)
			(effects
				(font
					(size 1.016 1.016)
					(thickness 0.1524)
				)
			)
		)
		(duplicate_pad_numbers_are_jumpers no)
		(fp_line
			(start 0.508 -0.9398)
			(end -0.508 -0.9398)
			(stroke
				(width 0.1524)
				(type default)
			)
			(layer "F.SilkS")
		)
		(fp_line
			(start -0.508 -0.9398)
			(end -0.508 0.9398)
			(stroke
				(width 0.1524)
				(type default)
			)
			(layer "F.SilkS")
		)
		(fp_rect
			(start -0.508 0.9398)
			(end 0.508 -0.9398)
			(stroke
				(width 0)
				(type default)
			)
			(fill no)
			(layer "F.CrtYd")
		)
		(fp_rect
			(start -0.508 0.9398)
			(end 0.508 -0.9398)
			(stroke
				(width 0)
				(type default)
			)
			(fill no)
			(layer "F.Fab")
		)
		(pad "1" smd custom
			(at 0 -0.4445 180)
			(size 0.1397 0.1397)
			(layers "F.Cu" "F.Mask" "F.Paste")
			(net "P3V3_STBY_A")
			(options
				(clearance outline)
				(anchor circle)
			)
			(primitives
				(gr_poly
					(pts
						(arc
							(start -0.1778 -0.2794)
							(mid -0.249642 -0.249642)
							(end -0.2794 -0.1778)
						)
						(arc
							(start -0.2794 0.1778)
							(mid -0.249642 0.249642)
							(end -0.1778 0.2794)
						)
						(arc
							(start 0.1778 0.2794)
							(mid 0.249642 0.249642)
							(end 0.2794 0.1778)
						)
						(arc
							(start 0.2794 -0.1778)
							(mid 0.249642 -0.249642)
							(end 0.1778 -0.2794)
						)
					)
					(width 0)
					(fill yes)
				)
			)
		)
		(pad "2" smd custom
			(at 0 0.4445 180)
			(size 0.1397 0.1397)
			(layers "F.Cu" "F.Mask" "F.Paste")
			(net "I2C_BMC_A_MISC_SCL")
			(options
				(clearance outline)
				(anchor circle)
			)
			(primitives
				(gr_poly
					(pts
						(arc
							(start -0.1778 -0.2794)
							(mid -0.249642 -0.249642)
							(end -0.2794 -0.1778)
						)
						(arc
							(start -0.2794 0.1778)
							(mid -0.249642 0.249642)
							(end -0.1778 0.2794)
						)
						(arc
							(start 0.1778 0.2794)
							(mid 0.249642 0.249642)
							(end 0.2794 0.1778)
						)
						(arc
							(start 0.2794 -0.1778)
							(mid 0.249642 -0.249642)
							(end 0.1778 -0.2794)
						)
					)
					(width 0)
					(fill yes)
				)
			)
		)
	)
	(footprint ""
		(layer "F.Cu")
		(at 232.41 -392.2268 -90)
		(property "Reference" "R1142"
			(at 0 0 270)
			(layer "F.SilkS")
			(hide yes)
			(effects
				(font
					(size 1.27 1.27)
				)
			)
		)
		(property "Value" "0R2J-2-GP"
			(at 0.064008 -3.993896 270)
			(unlocked yes)
			(layer "F.Fab")
			(hide yes)
			(effects
				(font
					(size 1.016 1.016)
					(thickness 0.1524)
				)
			)
		)
		(property "Device Type" "R402H16"
			(at 0.064008 -5.517896 270)
			(unlocked yes)
			(layer "F.Fab")
			(hide yes)
			(effects
				(font
					(size 1.016 1.016)
					(thickness 0.1524)
				)
			)
		)
		(duplicate_pad_numbers_are_jumpers no)
		(fp_line
			(start -0.508 -0.9398)
			(end -0.508 0.9398)
			(stroke
				(width 0.1524)
				(type default)
			)
			(layer "F.SilkS")
		)
		(fp_line
			(start 0.508 -0.9398)
			(end -0.508 -0.9398)
			(stroke
				(width 0.1524)
				(type default)
			)
			(layer "F.SilkS")
		)
		(fp_rect
			(start -0.508 0.9398)
			(end 0.508 -0.9398)
			(stroke
				(width 0)
				(type default)
			)
			(fill no)
			(layer "F.CrtYd")
		)
		(fp_rect
			(start -0.508 0.9398)
			(end 0.508 -0.9398)
			(stroke
				(width 0)
				(type default)
			)
			(fill no)
			(layer "F.Fab")
		)
		(pad "1" smd custom
			(at 0 -0.4445 270)
			(size 0.1397 0.1397)
			(layers "F.Cu" "F.Mask" "F.Paste")
			(net "MB3_CM_ADR2_R")
			(options
				(clearance outline)
				(anchor circle)
			)
			(primitives
				(gr_poly
					(pts
						(arc
							(start -0.1778 -0.2794)
							(mid -0.249642 -0.249642)
							(end -0.2794 -0.1778)
						)
						(arc
							(start -0.2794 0.1778)
							(mid -0.249642 0.249642)
							(end -0.1778 0.2794)
						)
						(arc
							(start 0.1778 0.2794)
							(mid 0.249642 0.249642)
							(end 0.2794 0.1778)
						)
						(arc
							(start 0.2794 -0.1778)
							(mid 0.249642 -0.249642)
							(end 0.1778 -0.2794)
						)
					)
					(width 0)
					(fill yes)
				)
			)
		)
		(pad "2" smd custom
			(at 0 0.4445 270)
			(size 0.1397 0.1397)
			(layers "F.Cu" "F.Mask" "F.Paste")
			(net "AGND_CURRENT_DPB")
			(options
				(clearance outline)
				(anchor circle)
			)
			(primitives
				(gr_poly
					(pts
						(arc
							(start -0.1778 -0.2794)
							(mid -0.249642 -0.249642)
							(end -0.2794 -0.1778)
						)
						(arc
							(start -0.2794 0.1778)
							(mid -0.249642 0.249642)
							(end -0.1778 0.2794)
						)
						(arc
							(start 0.1778 0.2794)
							(mid 0.249642 0.249642)
							(end 0.2794 0.1778)
						)
						(arc
							(start 0.2794 -0.1778)
							(mid 0.249642 -0.249642)
							(end 0.1778 -0.2794)
						)
					)
					(width 0)
					(fill yes)
				)
			)
		)
	)
)
